(kicad_pcb
	(version 20260206)
	(generator "pcbnew")
	(generator_version "10.0")
	(general
		(thickness 1.6)
		(legacy_teardrops no)
	)
	(paper "A4")
	(title_block
		(title "Wiwynn_Tioga_Pass_MB.brd")
		(comment 1 "Tioga Pass / footprints 4256-4262 of 4770")
	)
	(layers
		(0 "F.Cu" signal "TOP")
		(4 "In1.Cu" signal "L2GND")
		(6 "In2.Cu" signal "L3")
		(8 "In3.Cu" signal "L4GND")
		(10 "In4.Cu" signal "L5")
		(12 "In5.Cu" signal "L6GND")
		(14 "In6.Cu" signal "L7VCC")
		(16 "In7.Cu" signal "L8VCC")
		(18 "In8.Cu" signal "L9GND")
		(20 "In9.Cu" signal "L10")
		(22 "In10.Cu" signal "L11GND")
		(24 "In11.Cu" signal "L12")
		(26 "In12.Cu" signal "L13GND")
		(2 "B.Cu" signal "BOTTOM")
		(9 "F.Adhes" user "F.Adhesive")
		(11 "B.Adhes" user "B.Adhesive")
		(13 "F.Paste" user "Package Geometry/Pastemask Top")
		(15 "B.Paste" user "Package Geometry/Pastemask Bottom")
		(5 "F.SilkS" user "Ref Des/Silkscreen Top")
		(7 "B.SilkS" user "Ref Des/Silkscreen Bottom")
		(1 "F.Mask" user "Board Geometry/Soldermask Top")
		(3 "B.Mask" user "Board Geometry/Soldermask Bottom")
		(17 "Dwgs.User" user "User.Drawings")
		(19 "Cmts.User" user "User.Comments")
		(21 "Eco1.User" user "User.Eco1")
		(23 "Eco2.User" user "User.Eco2")
		(25 "Edge.Cuts" user "Board Geometry/Outline")
		(27 "Margin" user)
		(31 "F.CrtYd" user "Package Geometry/Place Bound Top")
		(29 "B.CrtYd" user "Package Geometry/Place Bound Bottom")
		(35 "F.Fab" user "Ref Des/Assembly Top")
		(33 "B.Fab" user "Ref Des/Assembly Bottom")
	)
	(footprint ""
		(layer "B.Cu")
		(at 108.559854 -79.60614 180)
		(property "Reference" "C7P7"
			(at 0 0 0)
			(layer "B.SilkS")
			(hide yes)
			(effects
				(font
					(size 1.27 1.27)
				)
				(justify mirror)
			)
		)
		(property "Value" ""
			(at 0 0 0)
			(layer "B.Fab")
			(effects
				(font
					(size 1.27 1.27)
				)
				(justify mirror)
			)
		)
		(duplicate_pad_numbers_are_jumpers no)
		(fp_poly
			(pts
				(xy 0.7239 -0.2159) (xy -0.7239 -0.2159) (xy -0.7239 1.9939) (xy 0.7239 1.9939)
			)
			(stroke
				(width 0)
				(type default)
			)
			(fill no)
			(layer "B.CrtYd")
		)
		(fp_line
			(start 0.7239 1.9939)
			(end -0.7239 1.9939)
			(stroke
				(width 0.1)
				(type default)
			)
			(layer "B.Fab")
		)
		(fp_line
			(start 0.7239 -0.2159)
			(end 0.7239 1.9939)
			(stroke
				(width 0.1)
				(type default)
			)
			(layer "B.Fab")
		)
		(fp_line
			(start -0.7239 1.9939)
			(end -0.7239 -0.2159)
			(stroke
				(width 0.1)
				(type default)
			)
			(layer "B.Fab")
		)
		(fp_line
			(start -0.7239 -0.2159)
			(end 0.7239 -0.2159)
			(stroke
				(width 0.1)
				(type default)
			)
			(layer "B.Fab")
		)
		(pad "1" smd rect
			(at 0 0)
			(size 1.27 1.016)
			(layers "B.Cu" "B.Mask" "B.Paste")
			(net "PVCCMCP_CPU1")
		)
		(pad "2" smd rect
			(at 0 1.778)
			(size 1.27 1.016)
			(layers "B.Cu" "B.Mask" "B.Paste")
			(net "GND")
		)
		(zone
			(layer "B.Cu")
			(hatch none 0.5)
			(connect_pads
				(clearance 0)
			)
			(min_thickness 0.25)
			(keepout
				(tracks not_allowed)
				(vias allowed)
				(pads allowed)
				(copperpour not_allowed)
				(footprints allowed)
			)
			(placement
				(enabled no)
				(sheetname "")
			)
			(fill
				(thermal_gap 0.5)
				(thermal_bridge_width 0.5)
				(island_removal_mode 0)
			)
			(polygon
				(pts
					(xy 107.924854 -80.11414) (xy 109.194854 -80.11414) (xy 109.194854 -80.87614) (xy 107.924854 -80.87614)
				)
			)
		)
	)
	(footprint ""
		(layer "B.Cu")
		(at 3.893312 -18.586196 90)
		(property "Reference" "C9T6"
			(at 0 0 90)
			(layer "B.SilkS")
			(hide yes)
			(effects
				(font
					(size 1.27 1.27)
				)
				(justify mirror)
			)
		)
		(property "Value" ""
			(at 0 0 90)
			(layer "B.Fab")
			(effects
				(font
					(size 1.27 1.27)
				)
				(justify mirror)
			)
		)
		(duplicate_pad_numbers_are_jumpers no)
		(fp_rect
			(start -0.7239 -0.2159)
			(end 0.7239 1.9939)
			(stroke
				(width 0)
				(type default)
			)
			(fill no)
			(layer "B.CrtYd")
		)
		(fp_line
			(start 0.7239 -0.2159)
			(end 0.7239 1.9939)
			(stroke
				(width 0.1)
				(type default)
			)
			(layer "B.Fab")
		)
		(fp_line
			(start -0.7239 -0.2159)
			(end 0.7239 -0.2159)
			(stroke
				(width 0.1)
				(type default)
			)
			(layer "B.Fab")
		)
		(fp_line
			(start 0.7239 1.9939)
			(end -0.7239 1.9939)
			(stroke
				(width 0.1)
				(type default)
			)
			(layer "B.Fab")
		)
		(fp_line
			(start -0.7239 1.9939)
			(end -0.7239 -0.2159)
			(stroke
				(width 0.1)
				(type default)
			)
			(layer "B.Fab")
		)
		(pad "1" smd rect
			(at 0 0 270)
			(size 1.27 1.016)
			(layers "B.Cu" "B.Mask" "B.Paste")
			(net "VR_FET_SW_P12V_STBY_PVDDQ_GHJ")
		)
		(pad "2" smd rect
			(at 0 1.778 270)
			(size 1.27 1.016)
			(layers "B.Cu" "B.Mask" "B.Paste")
			(net "GND")
		)
		(zone
			(layer "B.Cu")
			(hatch none 0.5)
			(connect_pads
				(clearance 0)
			)
			(min_thickness 0.25)
			(keepout
				(tracks not_allowed)
				(vias allowed)
				(pads allowed)
				(copperpour not_allowed)
				(footprints allowed)
			)
			(placement
				(enabled no)
				(sheetname "")
			)
			(fill
				(thermal_gap 0.5)
				(thermal_bridge_width 0.5)
				(island_removal_mode 0)
			)
			(polygon
				(pts
					(xy 4.401312 -17.951196) (xy 5.163312 -17.951196) (xy 5.163312 -19.221196) (xy 4.401312 -19.221196)
				)
			)
		)
	)
	(footprint ""
		(layer "B.Cu")
		(at 418.870638 -37.5285 -90)
		(property "Reference" "C25W51"
			(at 0.8382 -0.67818 270)
			(unlocked yes)
			(layer "B.SilkS")
			(effects
				(font
					(size 0.4064 0.254)
					(thickness 0.1524)
				)
				(justify left mirror)
			)
		)
		(property "Value" ""
			(at 0 0 90)
			(layer "B.Fab")
			(effects
				(font
					(size 1.27 1.27)
				)
				(justify mirror)
			)
		)
		(duplicate_pad_numbers_are_jumpers no)
		(fp_poly
			(pts
				(xy -0.3048 -0.1016) (xy -0.3048 0.9906) (xy 0.3048 0.9906) (xy 0.3048 -0.1016)
			)
			(stroke
				(width 0)
				(type default)
			)
			(fill no)
			(layer "B.CrtYd")
		)
		(fp_line
			(start -0.3048 0.9906)
			(end -0.3048 -0.1016)
			(stroke
				(width 0.1)
				(type default)
			)
			(layer "B.Fab")
		)
		(fp_line
			(start 0.3048 0.9906)
			(end -0.3048 0.9906)
			(stroke
				(width 0.1)
				(type default)
			)
			(layer "B.Fab")
		)
		(fp_line
			(start -0.3048 -0.1016)
			(end 0.3048 -0.1016)
			(stroke
				(width 0.1)
				(type default)
			)
			(layer "B.Fab")
		)
		(fp_line
			(start 0.3048 -0.1016)
			(end 0.3048 0.9906)
			(stroke
				(width 0.1)
				(type default)
			)
			(layer "B.Fab")
		)
		(pad "1" smd rect
			(at 0 0 90)
			(size 0.508 0.508)
			(layers "B.Cu" "B.Mask" "B.Paste")
			(net "P1V2_AUX_BMC")
		)
		(pad "2" smd rect
			(at 0 0.889 90)
			(size 0.508 0.508)
			(layers "B.Cu" "B.Mask" "B.Paste")
			(net "GND")
		)
		(zone
			(layer "B.Cu")
			(hatch none 0.5)
			(connect_pads
				(clearance 0)
			)
			(min_thickness 0.25)
			(keepout
				(tracks not_allowed)
				(vias allowed)
				(pads allowed)
				(copperpour not_allowed)
				(footprints allowed)
			)
			(placement
				(enabled no)
				(sheetname "")
			)
			(fill
				(thermal_gap 0.5)
				(thermal_bridge_width 0.5)
				(island_removal_mode 0)
			)
			(polygon
				(pts
					(xy 418.235638 -37.2745) (xy 418.235638 -37.7825) (xy 418.616638 -37.7825) (xy 418.616638 -37.2745)
				)
			)
		)
		(zone
			(layer "B.Cu")
			(hatch none 0.5)
			(connect_pads
				(clearance 0)
			)
			(min_thickness 0.25)
			(keepout
				(tracks allowed)
				(vias not_allowed)
				(pads allowed)
				(copperpour not_allowed)
				(footprints allowed)
			)
			(placement
				(enabled no)
				(sheetname "")
			)
			(fill
				(thermal_gap 0.5)
				(thermal_bridge_width 0.5)
				(island_removal_mode 0)
			)
			(polygon
				(pts
					(xy 418.616638 -37.2745) (xy 418.616638 -37.7825) (xy 418.235638 -37.7825) (xy 418.235638 -37.2745)
				)
			)
		)
	)
	(footprint ""
		(layer "B.Cu")
		(at 409.917646 -22.996652 -90)
		(property "Reference" "C25W50"
			(at -0.97536 0.76708 0)
			(unlocked yes)
			(layer "B.SilkS")
			(effects
				(font
					(size 0.4064 0.254)
					(thickness 0.1524)
				)
				(justify mirror)
			)
		)
		(property "Value" ""
			(at 0 0 90)
			(layer "B.Fab")
			(effects
				(font
					(size 1.27 1.27)
				)
				(justify mirror)
			)
		)
		(duplicate_pad_numbers_are_jumpers no)
		(fp_poly
			(pts
				(xy 0.4953 -0.2032) (xy -0.4953 -0.2032) (xy -0.4953 1.6002) (xy 0.4953 1.6002)
			)
			(stroke
				(width 0)
				(type default)
			)
			(fill no)
			(layer "B.CrtYd")
		)
		(fp_line
			(start -0.4953 1.6002)
			(end 0.4953 1.6002)
			(stroke
				(width 0.1)
				(type default)
			)
			(layer "B.Fab")
		)
		(fp_line
			(start 0.4953 1.6002)
			(end 0.4953 -0.2032)
			(stroke
				(width 0.1)
				(type default)
			)
			(layer "B.Fab")
		)
		(fp_line
			(start -0.4953 -0.2032)
			(end -0.4953 1.6002)
			(stroke
				(width 0.1)
				(type default)
			)
			(layer "B.Fab")
		)
		(fp_line
			(start 0.4953 -0.2032)
			(end -0.4953 -0.2032)
			(stroke
				(width 0.1)
				(type default)
			)
			(layer "B.Fab")
		)
		(pad "1" smd rect
			(at 0 0 90)
			(size 0.762 0.889)
			(layers "B.Cu" "B.Mask" "B.Paste")
			(net "P3V3_STBY")
		)
		(pad "2" smd rect
			(at 0 1.397 90)
			(size 0.762 0.889)
			(layers "B.Cu" "B.Mask" "B.Paste")
			(net "GND")
		)
		(zone
			(layer "B.Cu")
			(hatch none 0.5)
			(connect_pads
				(clearance 0)
			)
			(min_thickness 0.25)
			(keepout
				(tracks not_allowed)
				(vias allowed)
				(pads allowed)
				(copperpour not_allowed)
				(footprints allowed)
			)
			(placement
				(enabled no)
				(sheetname "")
			)
			(fill
				(thermal_gap 0.5)
				(thermal_bridge_width 0.5)
				(island_removal_mode 0)
			)
			(polygon
				(pts
					(xy 409.473146 -22.615652) (xy 409.473146 -23.377652) (xy 408.965146 -23.377652) (xy 408.965146 -22.615652)
				)
			)
		)
	)
	(footprint ""
		(layer "B.Cu")
		(at 160.76422 -123.9647)
		(property "Reference" "R7M1"
			(at 0 0 0)
			(layer "B.SilkS")
			(hide yes)
			(effects
				(font
					(size 1.27 1.27)
				)
				(justify mirror)
			)
		)
		(property "Value" ""
			(at 0 0 0)
			(layer "B.Fab")
			(effects
				(font
					(size 1.27 1.27)
				)
				(justify mirror)
			)
		)
		(duplicate_pad_numbers_are_jumpers no)
		(fp_poly
			(pts
				(xy 0.2794 -0.1016) (xy -0.2794 -0.1016) (xy -0.2794 0.9906) (xy 0.2794 0.9906)
			)
			(stroke
				(width 0)
				(type default)
			)
			(fill no)
			(layer "B.CrtYd")
		)
		(fp_line
			(start -0.2794 -0.1016)
			(end 0.2794 -0.1016)
			(stroke
				(width 0.1)
				(type default)
			)
			(layer "B.Fab")
		)
		(fp_line
			(start -0.2794 0.9906)
			(end -0.2794 -0.1016)
			(stroke
				(width 0.1)
				(type default)
			)
			(layer "B.Fab")
		)
		(fp_line
			(start 0.2794 -0.1016)
			(end 0.2794 0.9906)
			(stroke
				(width 0.1)
				(type default)
			)
			(layer "B.Fab")
		)
		(fp_line
			(start 0.2794 0.9906)
			(end -0.2794 0.9906)
			(stroke
				(width 0.1)
				(type default)
			)
			(layer "B.Fab")
		)
		(pad "1" smd rect
			(at 0 0 180)
			(size 0.508 0.508)
			(layers "B.Cu" "B.Mask" "B.Paste")
			(net "PVPP_KLM")
		)
		(pad "2" smd rect
			(at 0 0.889 180)
			(size 0.508 0.508)
			(layers "B.Cu" "B.Mask" "B.Paste")
			(net "SMB_DDR_KLM_VPP_SCL_R")
		)
		(zone
			(layer "B.Cu")
			(hatch none 0.5)
			(connect_pads
				(clearance 0)
			)
			(min_thickness 0.25)
			(keepout
				(tracks allowed)
				(vias not_allowed)
				(pads allowed)
				(copperpour not_allowed)
				(footprints allowed)
			)
			(placement
				(enabled no)
				(sheetname "")
			)
			(fill
				(thermal_gap 0.5)
				(thermal_bridge_width 0.5)
				(island_removal_mode 0)
			)
			(polygon
				(pts
					(xy 161.01822 -123.7107) (xy 160.51022 -123.7107) (xy 160.51022 -123.3297) (xy 161.01822 -123.3297)
				)
			)
		)
		(zone
			(layer "B.Cu")
			(hatch none 0.5)
			(connect_pads
				(clearance 0)
			)
			(min_thickness 0.25)
			(keepout
				(tracks not_allowed)
				(vias allowed)
				(pads allowed)
				(copperpour not_allowed)
				(footprints allowed)
			)
			(placement
				(enabled no)
				(sheetname "")
			)
			(fill
				(thermal_gap 0.5)
				(thermal_bridge_width 0.5)
				(island_removal_mode 0)
			)
			(polygon
				(pts
					(xy 161.01822 -123.3297) (xy 160.51022 -123.3297) (xy 160.51022 -123.7107) (xy 161.01822 -123.7107)
				)
			)
		)
	)
	(footprint ""
		(layer "B.Cu")
		(at 390.635744 -24.981916 -90)
		(property "Reference" "C2T16"
			(at 0 0 90)
			(layer "B.SilkS")
			(hide yes)
			(effects
				(font
					(size 1.27 1.27)
				)
				(justify mirror)
			)
		)
		(property "Value" ""
			(at 0 0 90)
			(layer "B.Fab")
			(effects
				(font
					(size 1.27 1.27)
				)
				(justify mirror)
			)
		)
		(duplicate_pad_numbers_are_jumpers no)
		(fp_poly
			(pts
				(xy -0.3048 -0.1016) (xy -0.3048 0.9906) (xy 0.3048 0.9906) (xy 0.3048 -0.1016)
			)
			(stroke
				(width 0)
				(type default)
			)
			(fill no)
			(layer "B.CrtYd")
		)
		(fp_line
			(start -0.3048 0.9906)
			(end -0.3048 -0.1016)
			(stroke
				(width 0.1)
				(type default)
			)
			(layer "B.Fab")
		)
		(fp_line
			(start 0.3048 0.9906)
			(end -0.3048 0.9906)
			(stroke
				(width 0.1)
				(type default)
			)
			(layer "B.Fab")
		)
		(fp_line
			(start -0.3048 -0.1016)
			(end 0.3048 -0.1016)
			(stroke
				(width 0.1)
				(type default)
			)
			(layer "B.Fab")
		)
		(fp_line
			(start 0.3048 -0.1016)
			(end 0.3048 0.9906)
			(stroke
				(width 0.1)
				(type default)
			)
			(layer "B.Fab")
		)
		(pad "1" smd rect
			(at 0 0 90)
			(size 0.508 0.508)
			(layers "B.Cu" "B.Mask" "B.Paste")
			(net "P3V3")
		)
		(pad "2" smd rect
			(at 0 0.889 90)
			(size 0.508 0.508)
			(layers "B.Cu" "B.Mask" "B.Paste")
			(net "GND")
		)
		(zone
			(layer "B.Cu")
			(hatch none 0.5)
			(connect_pads
				(clearance 0)
			)
			(min_thickness 0.25)
			(keepout
				(tracks not_allowed)
				(vias allowed)
				(pads allowed)
				(copperpour not_allowed)
				(footprints allowed)
			)
			(placement
				(enabled no)
				(sheetname "")
			)
			(fill
				(thermal_gap 0.5)
				(thermal_bridge_width 0.5)
				(island_removal_mode 0)
			)
			(polygon
				(pts
					(xy 390.000744 -24.727916) (xy 390.000744 -25.235916) (xy 390.381744 -25.235916) (xy 390.381744 -24.727916)
				)
			)
		)
		(zone
			(layer "B.Cu")
			(hatch none 0.5)
			(connect_pads
				(clearance 0)
			)
			(min_thickness 0.25)
			(keepout
				(tracks allowed)
				(vias not_allowed)
				(pads allowed)
				(copperpour not_allowed)
				(footprints allowed)
			)
			(placement
				(enabled no)
				(sheetname "")
			)
			(fill
				(thermal_gap 0.5)
				(thermal_bridge_width 0.5)
				(island_removal_mode 0)
			)
			(polygon
				(pts
					(xy 390.381744 -24.727916) (xy 390.381744 -25.235916) (xy 390.000744 -25.235916) (xy 390.000744 -24.727916)
				)
			)
		)
	)
	(footprint ""
		(layer "B.Cu")
		(at 354.301806 -61.257434)
		(property "Reference" "C2U18"
			(at 0 0 0)
			(layer "B.SilkS")
			(hide yes)
			(effects
				(font
					(size 1.27 1.27)
				)
				(justify mirror)
			)
		)
		(property "Value" ""
			(at 0 0 0)
			(layer "B.Fab")
			(effects
				(font
					(size 1.27 1.27)
				)
				(justify mirror)
			)
		)
		(duplicate_pad_numbers_are_jumpers no)
		(fp_poly
			(pts
				(xy -0.3048 -0.1016) (xy -0.3048 0.9906) (xy 0.3048 0.9906) (xy 0.3048 -0.1016)
			)
			(stroke
				(width 0)
				(type default)
			)
			(fill no)
			(layer "B.CrtYd")
		)
		(fp_line
			(start -0.3048 -0.1016)
			(end 0.3048 -0.1016)
			(stroke
				(width 0.1)
				(type default)
			)
			(layer "B.Fab")
		)
		(fp_line
			(start -0.3048 0.9906)
			(end -0.3048 -0.1016)
			(stroke
				(width 0.1)
				(type default)
			)
			(layer "B.Fab")
		)
		(fp_line
			(start 0.3048 -0.1016)
			(end 0.3048 0.9906)
			(stroke
				(width 0.1)
				(type default)
			)
			(layer "B.Fab")
		)
		(fp_line
			(start 0.3048 0.9906)
			(end -0.3048 0.9906)
			(stroke
				(width 0.1)
				(type default)
			)
			(layer "B.Fab")
		)
		(pad "1" smd rect
			(at 0 0 180)
			(size 0.508 0.508)
			(layers "B.Cu" "B.Mask" "B.Paste")
			(net "P3E_CPU0_PE1_PCH_RXN<7>")
		)
		(pad "2" smd rect
			(at 0 0.889 180)
			(size 0.508 0.508)
			(layers "B.Cu" "B.Mask" "B.Paste")
			(net "P3E_CPU0_PE1_SS_RXN<7>")
		)
		(zone
			(layer "B.Cu")
			(hatch none 0.5)
			(connect_pads
				(clearance 0)
			)
			(min_thickness 0.25)
			(keepout
				(tracks allowed)
				(vias not_allowed)
				(pads allowed)
				(copperpour not_allowed)
				(footprints allowed)
			)
			(placement
				(enabled no)
				(sheetname "")
			)
			(fill
				(thermal_gap 0.5)
				(thermal_bridge_width 0.5)
				(island_removal_mode 0)
			)
			(polygon
				(pts
					(xy 354.555806 -61.003434) (xy 354.047806 -61.003434) (xy 354.047806 -60.622434) (xy 354.555806 -60.622434)
				)
			)
		)
		(zone
			(layer "B.Cu")
			(hatch none 0.5)
			(connect_pads
				(clearance 0)
			)
			(min_thickness 0.25)
			(keepout
				(tracks not_allowed)
				(vias allowed)
				(pads allowed)
				(copperpour not_allowed)
				(footprints allowed)
			)
			(placement
				(enabled no)
				(sheetname "")
			)
			(fill
				(thermal_gap 0.5)
				(thermal_bridge_width 0.5)
				(island_removal_mode 0)
			)
			(polygon
				(pts
					(xy 354.555806 -60.622434) (xy 354.047806 -60.622434) (xy 354.047806 -61.003434) (xy 354.555806 -61.003434)
				)
			)
		)
	)
)
